# BASEBOARD_FAB2 (Tioga Pass) — schematic netlist excerpt (pin names and nets, part order shuffled) for the footprints in the layout excerpt that follows; sources: Cadence DE-HDL packaged netlist, KiCad conversion of Wiwynn_Tioga_Pass_MB.brd

C2D36  CAP_A  22.0UF 4V 20% X6S  pkg 0603V  page 76 : A = PVCCIN_CPU1 ; B = GND
C4A17  CAP  10UF 16V 10% X7R  pkg 0805  page 197 : A = P12V_NVDIMM_DEF ; B = GND
R7F9  RES  0.0 5% CHIP  pkg 0402  page 231 : A = FM_PVPP_CPU0_EN ; B = FM_PVPP_PVDDQ_CPU0_EN_ABC

(kicad_pcb
	(version 20260206)
	(generator "pcbnew")
	(generator_version "10.0")
	(general
		(thickness 1.6)
		(legacy_teardrops no)
	)
	(paper "A4")
	(title_block
		(title "Wiwynn_Tioga_Pass_MB.brd")
		(comment 1 "Tioga Pass / footprints 1524-1526 of 4770")
	)
	(layers
		(0 "F.Cu" signal "TOP")
		(4 "In1.Cu" signal "L2GND")
		(6 "In2.Cu" signal "L3")
		(8 "In3.Cu" signal "L4GND")
		(10 "In4.Cu" signal "L5")
		(12 "In5.Cu" signal "L6GND")
		(14 "In6.Cu" signal "L7VCC")
		(16 "In7.Cu" signal "L8VCC")
		(18 "In8.Cu" signal "L9GND")
		(20 "In9.Cu" signal "L10")
		(22 "In10.Cu" signal "L11GND")
		(24 "In11.Cu" signal "L12")
		(26 "In12.Cu" signal "L13GND")
		(2 "B.Cu" signal "BOTTOM")
		(9 "F.Adhes" user "F.Adhesive")
		(11 "B.Adhes" user "B.Adhesive")
		(13 "F.Paste" user "Package Geometry/Pastemask Top")
		(15 "B.Paste" user "Package Geometry/Pastemask Bottom")
		(5 "F.SilkS" user "Ref Des/Silkscreen Top")
		(7 "B.SilkS" user "Ref Des/Silkscreen Bottom")
		(1 "F.Mask" user "Board Geometry/Soldermask Top")
		(3 "B.Mask" user "Board Geometry/Soldermask Bottom")
		(17 "Dwgs.User" user "User.Drawings")
		(19 "Cmts.User" user "User.Comments")
		(21 "Eco1.User" user "User.Eco1")
		(23 "Eco2.User" user "User.Eco2")
		(25 "Edge.Cuts" user "Board Geometry/Outline")
		(27 "Margin" user)
		(31 "F.CrtYd" user "Package Geometry/Place Bound Top")
		(29 "B.CrtYd" user "Package Geometry/Place Bound Bottom")
		(35 "F.Fab" user "Ref Des/Assembly Top")
		(33 "B.Fab" user "Ref Des/Assembly Bottom")
	)
	(footprint ""
		(layer "F.Cu")
		(at 340.806278 -24.508206 90)
		(property "Reference" "R7F9"
			(at 0 0 90)
			(layer "F.SilkS")
			(hide yes)
			(effects
				(font
					(size 1.27 1.27)
				)
			)
		)
		(property "Value" ""
			(at 0 0 90)
			(layer "F.Fab")
			(effects
				(font
					(size 1.27 1.27)
				)
			)
		)
		(duplicate_pad_numbers_are_jumpers no)
		(fp_poly
			(pts
				(xy -0.2794 -0.1016) (xy 0.2794 -0.1016) (xy 0.2794 0.9906) (xy -0.2794 0.9906)
			)
			(stroke
				(width 0)
				(type default)
			)
			(fill no)
			(layer "F.CrtYd")
		)
		(fp_line
			(start 0.2794 -0.1016)
			(end -0.2794 -0.1016)
			(stroke
				(width 0.1)
				(type default)
			)
			(layer "F.Fab")
		)
		(fp_line
			(start -0.2794 -0.1016)
			(end -0.2794 0.9906)
			(stroke
				(width 0.1)
				(type default)
			)
			(layer "F.Fab")
		)
		(fp_line
			(start 0.2794 0.9906)
			(end 0.2794 -0.1016)
			(stroke
				(width 0.1)
				(type default)
			)
			(layer "F.Fab")
		)
		(fp_line
			(start -0.2794 0.9906)
			(end 0.2794 0.9906)
			(stroke
				(width 0.1)
				(type default)
			)
			(layer "F.Fab")
		)
		(pad "1" smd rect
			(at 0 0 90)
			(size 0.508 0.508)
			(layers "F.Cu" "F.Mask" "F.Paste")
			(net "FM_PVPP_CPU0_EN")
		)
		(pad "2" smd rect
			(at 0 0.889 90)
			(size 0.508 0.508)
			(layers "F.Cu" "F.Mask" "F.Paste")
			(net "FM_PVPP_PVDDQ_CPU0_EN_ABC")
		)
		(zone
			(layer "F.Cu")
			(hatch none 0.5)
			(connect_pads
				(clearance 0)
			)
			(min_thickness 0.25)
			(keepout
				(tracks allowed)
				(vias not_allowed)
				(pads allowed)
				(copperpour not_allowed)
				(footprints allowed)
			)
			(placement
				(enabled no)
				(sheetname "")
			)
			(fill
				(thermal_gap 0.5)
				(thermal_bridge_width 0.5)
				(island_removal_mode 0)
			)
			(polygon
				(pts
					(xy 341.060278 -24.254206) (xy 341.060278 -24.762206) (xy 341.441278 -24.762206) (xy 341.441278 -24.254206)
				)
			)
		)
		(zone
			(layer "F.Cu")
			(hatch none 0.5)
			(connect_pads
				(clearance 0)
			)
			(min_thickness 0.25)
			(keepout
				(tracks not_allowed)
				(vias allowed)
				(pads allowed)
				(copperpour not_allowed)
				(footprints allowed)
			)
			(placement
				(enabled no)
				(sheetname "")
			)
			(fill
				(thermal_gap 0.5)
				(thermal_bridge_width 0.5)
				(island_removal_mode 0)
			)
			(polygon
				(pts
					(xy 341.441278 -24.254206) (xy 341.441278 -24.762206) (xy 341.060278 -24.762206) (xy 341.060278 -24.254206)
				)
			)
		)
	)
	(footprint ""
		(layer "F.Cu")
		(at 193.127122 -140.177012 -90)
		(property "Reference" "C4A17"
			(at 0 0 270)
			(layer "F.SilkS")
			(hide yes)
			(effects
				(font
					(size 1.27 1.27)
				)
			)
		)
		(property "Value" ""
			(at 0 0 270)
			(layer "F.Fab")
			(effects
				(font
					(size 1.27 1.27)
				)
			)
		)
		(duplicate_pad_numbers_are_jumpers no)
		(fp_rect
			(start -0.7239 1.9939)
			(end 0.7239 -0.2159)
			(stroke
				(width 0)
				(type default)
			)
			(fill no)
			(layer "F.CrtYd")
		)
		(fp_line
			(start -0.7239 1.9939)
			(end 0.7239 1.9939)
			(stroke
				(width 0.1)
				(type default)
			)
			(layer "F.Fab")
		)
		(fp_line
			(start 0.7239 1.9939)
			(end 0.7239 -0.2159)
			(stroke
				(width 0.1)
				(type default)
			)
			(layer "F.Fab")
		)
		(fp_line
			(start -0.7239 -0.2159)
			(end -0.7239 1.9939)
			(stroke
				(width 0.1)
				(type default)
			)
			(layer "F.Fab")
		)
		(fp_line
			(start 0.7239 -0.2159)
			(end -0.7239 -0.2159)
			(stroke
				(width 0.1)
				(type default)
			)
			(layer "F.Fab")
		)
		(pad "1" smd rect
			(at 0 0 270)
			(size 1.27 1.016)
			(layers "F.Cu" "F.Mask" "F.Paste")
			(net "P12V_NVDIMM_DEF")
		)
		(pad "2" smd rect
			(at 0 1.778 270)
			(size 1.27 1.016)
			(layers "F.Cu" "F.Mask" "F.Paste")
			(net "GND")
		)
		(zone
			(layer "F.Cu")
			(hatch none 0.5)
			(connect_pads
				(clearance 0)
			)
			(min_thickness 0.25)
			(keepout
				(tracks not_allowed)
				(vias allowed)
				(pads allowed)
				(copperpour not_allowed)
				(footprints allowed)
			)
			(placement
				(enabled no)
				(sheetname "")
			)
			(fill
				(thermal_gap 0.5)
				(thermal_bridge_width 0.5)
				(island_removal_mode 0)
			)
			(polygon
				(pts
					(xy 191.857122 -140.812012) (xy 191.857122 -139.542012) (xy 192.619122 -139.542012) (xy 192.619122 -140.812012)
				)
			)
		)
	)
	(footprint ""
		(layer "F.Cu")
		(at 100.67544 -73.318116)
		(property "Reference" "C2D36"
			(at 0 0 0)
			(layer "F.SilkS")
			(hide yes)
			(effects
				(font
					(size 1.27 1.27)
				)
			)
		)
		(property "Value" ""
			(at 0 0 0)
			(layer "F.Fab")
			(effects
				(font
					(size 1.27 1.27)
				)
			)
		)
		(duplicate_pad_numbers_are_jumpers no)
		(fp_poly
			(pts
				(xy -0.4953 -0.2032) (xy 0.4953 -0.2032) (xy 0.4953 1.6002) (xy -0.4953 1.6002)
			)
			(stroke
				(width 0)
				(type default)
			)
			(fill no)
			(layer "F.CrtYd")
		)
		(fp_line
			(start -0.4953 -0.2032)
			(end 0.4953 -0.2032)
			(stroke
				(width 0.1)
				(type default)
			)
			(layer "F.Fab")
		)
		(fp_line
			(start -0.4953 1.6002)
			(end -0.4953 -0.2032)
			(stroke
				(width 0.1)
				(type default)
			)
			(layer "F.Fab")
		)
		(fp_line
			(start 0.4953 -0.2032)
			(end 0.4953 1.6002)
			(stroke
				(width 0.1)
				(type default)
			)
			(layer "F.Fab")
		)
		(fp_line
			(start 0.4953 1.6002)
			(end -0.4953 1.6002)
			(stroke
				(width 0.1)
				(type default)
			)
			(layer "F.Fab")
		)
		(pad "1" smd rect
			(at 0 0)
			(size 0.762 0.889)
			(layers "F.Cu" "F.Mask" "F.Paste")
			(net "PVCCIN_CPU1")
		)
		(pad "2" smd rect
			(at 0 1.397)
			(size 0.762 0.889)
			(layers "F.Cu" "F.Mask" "F.Paste")
			(net "GND")
		)
		(zone
			(layer "F.Cu")
			(hatch none 0.5)
			(connect_pads
				(clearance 0)
			)
			(min_thickness 0.25)
			(keepout
				(tracks not_allowed)
				(vias allowed)
				(pads allowed)
				(copperpour not_allowed)
				(footprints allowed)
			)
			(placement
				(enabled no)
				(sheetname "")
			)
			(fill
				(thermal_gap 0.5)
				(thermal_bridge_width 0.5)
				(island_removal_mode 0)
			)
			(polygon
				(pts
					(xy 100.29444 -72.873616) (xy 101.05644 -72.873616) (xy 101.05644 -72.365616) (xy 100.29444 -72.365616)
				)
			)
		)
	)
)
